# T6G (Grand Teton) — schematic netlist excerpt (pin names and nets, part order shuffled) for the footprints in the layout excerpt that follows; sources: Cadence DE-HDL packaged netlist, KiCad conversion of 04192023_DAF0TMB3IC0_F0TG_MB_C_brd_V02_OCP.brd

R825  Q_RES  10K 5% EMPTY  pkg 0402LF  page 164 : A = P3V3_AUX ; B = UART_CPU0_LVC3_UART0_RX
H89  HOLE  EMPTY  pkg TH  page 230 : \1\ = GND
R939  Q_RES  0 5% CHIP  pkg 0402LF  page 28 : A = FM_BIOS_POST_CMPLT_R_N ; B = FM_BIOS_POST_CMPLT_N

(kicad_pcb
	(version 20260206)
	(generator "pcbnew")
	(generator_version "10.0")
	(general
		(thickness 1.6)
		(legacy_teardrops no)
	)
	(paper "A4")
	(title_block
		(title "04192023_DAF0TMB3IC0_F0TG_MB_C_brd_V02_OCP.brd")
		(comment 1 "Grand Teton / footprints 4727-4729 of 8354")
	)
	(layers
		(0 "F.Cu" signal "TOP")
		(4 "In1.Cu" signal "GND")
		(6 "In2.Cu" signal "IN1")
		(8 "In3.Cu" signal "GND1")
		(10 "In4.Cu" signal "IN2")
		(12 "In5.Cu" signal "GND2")
		(14 "In6.Cu" signal "IN3")
		(16 "In7.Cu" signal "GND3")
		(18 "In8.Cu" signal "VCC")
		(20 "In9.Cu" signal "VCC1")
		(22 "In10.Cu" signal "GND4")
		(24 "In11.Cu" signal "IN4")
		(26 "In12.Cu" signal "GND5")
		(28 "In13.Cu" signal "IN5")
		(30 "In14.Cu" signal "GND6")
		(32 "In15.Cu" signal "IN6")
		(34 "In16.Cu" signal "GND7")
		(2 "B.Cu" signal "BOTTOM")
		(9 "F.Adhes" user "F.Adhesive")
		(11 "B.Adhes" user "B.Adhesive")
		(13 "F.Paste" user "Package Geometry/Pastemask Top")
		(15 "B.Paste" user "Package Geometry/Pastemask Bottom")
		(5 "F.SilkS" user "Ref Des/Silkscreen Top")
		(7 "B.SilkS" user "Ref Des/Silkscreen Bottom")
		(1 "F.Mask" user "Board Geometry/Soldermask Top")
		(3 "B.Mask" user "Board Geometry/Soldermask Bottom")
		(17 "Dwgs.User" user "User.Drawings")
		(19 "Cmts.User" user "User.Comments")
		(21 "Eco1.User" user "User.Eco1")
		(23 "Eco2.User" user "User.Eco2")
		(25 "Edge.Cuts" user "Board Geometry/Outline")
		(27 "Margin" user)
		(31 "F.CrtYd" user "Package Geometry/Place Bound Top")
		(29 "B.CrtYd" user "Package Geometry/Place Bound Bottom")
		(35 "F.Fab" user "Ref Des/Assembly Top")
		(33 "B.Fab" user "Ref Des/Assembly Bottom")
	)
	(footprint ""
		(layer "F.Cu")
		(at 365.518446 -28.306522 90)
		(property "Reference" "R825"
			(at 0 0 90)
			(layer "F.SilkS")
			(hide yes)
			(effects
				(font
					(size 1.27 1.27)
				)
			)
		)
		(property "Value" ""
			(at 0 0 90)
			(layer "F.Fab")
			(effects
				(font
					(size 1.27 1.27)
				)
			)
		)
		(duplicate_pad_numbers_are_jumpers no)
		(fp_line
			(start 0.7874 -0.4064)
			(end 0.7874 0.4064)
			(stroke
				(width 0.1524)
				(type default)
			)
			(layer "F.SilkS")
		)
		(fp_line
			(start -0.7874 -0.4064)
			(end 0.7874 -0.4064)
			(stroke
				(width 0.1524)
				(type default)
			)
			(layer "F.SilkS")
		)
		(fp_line
			(start 0.7874 0.4064)
			(end -0.7874 0.4064)
			(stroke
				(width 0.1524)
				(type default)
			)
			(layer "F.SilkS")
		)
		(fp_line
			(start -0.7874 0.4064)
			(end -0.7874 -0.4064)
			(stroke
				(width 0.1524)
				(type default)
			)
			(layer "F.SilkS")
		)
		(fp_line
			(start -0.12065 -0.305054)
			(end -0.12065 -0.2794)
			(stroke
				(width 0.1)
				(type default)
			)
			(layer "F.Fab")
		)
		(fp_line
			(start -0.67945 -0.305054)
			(end -0.12065 -0.305054)
			(stroke
				(width 0.1)
				(type default)
			)
			(layer "F.Fab")
		)
		(fp_line
			(start 0.67945 -0.3048)
			(end 0.67945 0.3048)
			(stroke
				(width 0.1)
				(type default)
			)
			(layer "F.Fab")
		)
		(fp_line
			(start 0.12065 -0.3048)
			(end 0.67945 -0.3048)
			(stroke
				(width 0.1)
				(type default)
			)
			(layer "F.Fab")
		)
		(fp_line
			(start 0.12065 -0.2794)
			(end 0.12065 -0.3048)
			(stroke
				(width 0.1)
				(type default)
			)
			(layer "F.Fab")
		)
		(fp_line
			(start -0.12065 -0.2794)
			(end 0.12065 -0.2794)
			(stroke
				(width 0.1)
				(type default)
			)
			(layer "F.Fab")
		)
		(fp_line
			(start 0.120396 0.2794)
			(end -0.12065 0.2794)
			(stroke
				(width 0.1)
				(type default)
			)
			(layer "F.Fab")
		)
		(fp_line
			(start -0.12065 0.2794)
			(end -0.12065 0.3048)
			(stroke
				(width 0.1)
				(type default)
			)
			(layer "F.Fab")
		)
		(fp_line
			(start 0.67945 0.3048)
			(end 0.120396 0.3048)
			(stroke
				(width 0.1)
				(type default)
			)
			(layer "F.Fab")
		)
		(fp_line
			(start 0.120396 0.3048)
			(end 0.120396 0.2794)
			(stroke
				(width 0.1)
				(type default)
			)
			(layer "F.Fab")
		)
		(fp_line
			(start -0.12065 0.3048)
			(end -0.67945 0.3048)
			(stroke
				(width 0.1)
				(type default)
			)
			(layer "F.Fab")
		)
		(fp_line
			(start -0.67945 0.3048)
			(end -0.67945 -0.305054)
			(stroke
				(width 0.1)
				(type default)
			)
			(layer "F.Fab")
		)
		(pad "1" smd circle
			(at -0.40005 0 90)
			(size 0 0)
			(layers "F.Cu" "F.Mask" "F.Paste")
			(net "P3V3_AUX")
		)
		(pad "2" smd circle
			(at 0.40005 0 90)
			(size 0 0)
			(layers "F.Cu" "F.Mask" "F.Paste")
			(net "UART_CPU0_LVC3_UART0_RX")
		)
	)
	(footprint ""
		(layer "F.Cu")
		(at 382.391158 -323.186552 90)
		(property "Reference" "R939"
			(at 0 0 90)
			(layer "F.SilkS")
			(hide yes)
			(effects
				(font
					(size 1.27 1.27)
				)
			)
		)
		(property "Value" ""
			(at 0 0 90)
			(layer "F.Fab")
			(effects
				(font
					(size 1.27 1.27)
				)
			)
		)
		(duplicate_pad_numbers_are_jumpers no)
		(fp_line
			(start 0.7874 -0.4064)
			(end 0.7874 0.4064)
			(stroke
				(width 0.1524)
				(type default)
			)
			(layer "F.SilkS")
		)
		(fp_line
			(start -0.7874 -0.4064)
			(end 0.7874 -0.4064)
			(stroke
				(width 0.1524)
				(type default)
			)
			(layer "F.SilkS")
		)
		(fp_line
			(start 0.7874 0.4064)
			(end -0.7874 0.4064)
			(stroke
				(width 0.1524)
				(type default)
			)
			(layer "F.SilkS")
		)
		(fp_line
			(start -0.7874 0.4064)
			(end -0.7874 -0.4064)
			(stroke
				(width 0.1524)
				(type default)
			)
			(layer "F.SilkS")
		)
		(fp_line
			(start -0.12065 -0.305054)
			(end -0.12065 -0.2794)
			(stroke
				(width 0.1)
				(type default)
			)
			(layer "F.Fab")
		)
		(fp_line
			(start -0.67945 -0.305054)
			(end -0.12065 -0.305054)
			(stroke
				(width 0.1)
				(type default)
			)
			(layer "F.Fab")
		)
		(fp_line
			(start 0.67945 -0.3048)
			(end 0.67945 0.3048)
			(stroke
				(width 0.1)
				(type default)
			)
			(layer "F.Fab")
		)
		(fp_line
			(start 0.12065 -0.3048)
			(end 0.67945 -0.3048)
			(stroke
				(width 0.1)
				(type default)
			)
			(layer "F.Fab")
		)
		(fp_line
			(start 0.12065 -0.2794)
			(end 0.12065 -0.3048)
			(stroke
				(width 0.1)
				(type default)
			)
			(layer "F.Fab")
		)
		(fp_line
			(start -0.12065 -0.2794)
			(end 0.12065 -0.2794)
			(stroke
				(width 0.1)
				(type default)
			)
			(layer "F.Fab")
		)
		(fp_line
			(start 0.120396 0.2794)
			(end -0.12065 0.2794)
			(stroke
				(width 0.1)
				(type default)
			)
			(layer "F.Fab")
		)
		(fp_line
			(start -0.12065 0.2794)
			(end -0.12065 0.3048)
			(stroke
				(width 0.1)
				(type default)
			)
			(layer "F.Fab")
		)
		(fp_line
			(start 0.67945 0.3048)
			(end 0.120396 0.3048)
			(stroke
				(width 0.1)
				(type default)
			)
			(layer "F.Fab")
		)
		(fp_line
			(start 0.120396 0.3048)
			(end 0.120396 0.2794)
			(stroke
				(width 0.1)
				(type default)
			)
			(layer "F.Fab")
		)
		(fp_line
			(start -0.12065 0.3048)
			(end -0.67945 0.3048)
			(stroke
				(width 0.1)
				(type default)
			)
			(layer "F.Fab")
		)
		(fp_line
			(start -0.67945 0.3048)
			(end -0.67945 -0.305054)
			(stroke
				(width 0.1)
				(type default)
			)
			(layer "F.Fab")
		)
		(pad "1" smd circle
			(at -0.40005 0 90)
			(size 0 0)
			(layers "F.Cu" "F.Mask" "F.Paste")
			(net "FM_BIOS_POST_CMPLT_R_N")
		)
		(pad "2" smd circle
			(at 0.40005 0 90)
			(size 0 0)
			(layers "F.Cu" "F.Mask" "F.Paste")
			(net "FM_BIOS_POST_CMPLT_N")
		)
	)
	(footprint ""
		(layer "F.Cu")
		(at 167.900096 -160.50006)
		(property "Reference" "H89"
			(at -5.028184 -6.468618 0)
			(unlocked yes)
			(layer "F.SilkS")
			(effects
				(font
					(size 0.7874 0.5842)
					(thickness 0.1524)
				)
				(justify left)
			)
		)
		(property "Value" ""
			(at 0 0 0)
			(layer "F.Fab")
			(effects
				(font
					(size 1.27 1.27)
				)
			)
		)
		(duplicate_pad_numbers_are_jumpers no)
		(pad "1" thru_hole circle
			(at 0 0)
			(size 10.0076 10.0076)
			(drill 5.6134)
			(layers "*.Cu" "*.Mask")
			(remove_unused_layers no)
			(net "GND")
			(clearance -1.9431)
		)
	)
)
